(kicad_pcb
	(version 20241229)
	(generator "pcbnew")
	(generator_version "9.0")
	(general
		(thickness 1.711)
		(legacy_teardrops no)
	)
	(paper "A4")
	(title_block
		(title "Antmicro Baseboard for Jetson AGX Thor")
		(date "2026-02-18")
		(rev "1.1.0")
		(company "Antmicro Ltd")
		(comment 1 "www.antmicro.com")
		(comment 9 "footprints 655-657 of 1170")
	)
	(layers
		(0 "F.Cu" signal)
		(4 "In1.Cu" signal)
		(6 "In2.Cu" signal)
		(8 "In3.Cu" signal)
		(10 "In4.Cu" jumper)
		(12 "In5.Cu" signal)
		(14 "In6.Cu" signal)
		(16 "In7.Cu" signal)
		(18 "In8.Cu" signal)
		(2 "B.Cu" signal)
		(9 "F.Adhes" user "F.Adhesive")
		(11 "B.Adhes" user "B.Adhesive")
		(13 "F.Paste" user)
		(15 "B.Paste" user)
		(5 "F.SilkS" user "F.Silkscreen")
		(7 "B.SilkS" user "B.Silkscreen")
		(1 "F.Mask" user)
		(3 "B.Mask" user)
		(17 "Dwgs.User" user "User.Drawings")
		(19 "Cmts.User" user "User.Comments")
		(21 "Eco1.User" user "User.Eco1")
		(23 "Eco2.User" user "User.Eco2")
		(25 "Edge.Cuts" user)
		(27 "Margin" user)
		(31 "F.CrtYd" user "F.Courtyard")
		(29 "B.CrtYd" user "B.Courtyard")
		(35 "F.Fab" user)
		(33 "B.Fab" user)
	)
	(footprint "antmicro-footprints:C_0805_2012Metric"
		(layer "B.Cu")
		(at 229.4 82.4 180)
		(descr "Capacitor SMD 0805")
		(tags "capacitor SMD 0805")
		(property "Reference" "C151"
			(at -0.1 1 0)
			(layer "B.SilkS")
			(effects
				(font
					(size 0.7 0.7)
					(thickness 0.15)
				)
				(justify left bottom mirror)
			)
		)
		(property "Value" "C_22u_25V_0805"
			(at -2.055717 -1.963153 0)
			(layer "B.Fab")
			(effects
				(font
					(size 0.7 0.7)
					(thickness 0.15)
				)
				(justify left bottom mirror)
			)
		)
		(property "Datasheet" "https://product.samsungsem.com/mlcc/CL21A226MAYNNN.do"
			(at 0 0 0)
			(layer "B.Fab")
			(hide yes)
			(effects
				(font
					(size 1.27 1.27)
					(thickness 0.15)
				)
				(justify mirror)
			)
		)
		(property "Description" "SMT Multilayer Ceramic Capacitor, 22uF, +/-20%, 25V, X5R, 0805 [2012 Metric]"
			(at 0 0 0)
			(layer "B.Fab")
			(hide yes)
			(effects
				(font
					(size 1.27 1.27)
					(thickness 0.15)
				)
				(justify mirror)
			)
		)
		(property "Manufacturer" "Samsung Electro-Mechanics"
			(at 0 0 180)
			(unlocked yes)
			(layer "B.Fab")
			(hide yes)
			(effects
				(font
					(size 1 1)
					(thickness 0.15)
				)
				(justify mirror)
			)
		)
		(property "MPN" "CL21A226MAYNNNE"
			(at 0 0 180)
			(unlocked yes)
			(layer "B.Fab")
			(hide yes)
			(effects
				(font
					(size 1 1)
					(thickness 0.15)
				)
				(justify mirror)
			)
		)
		(property "Val" "22u"
			(at 0 0 180)
			(unlocked yes)
			(layer "B.Fab")
			(hide yes)
			(effects
				(font
					(size 1 1)
					(thickness 0.15)
				)
				(justify mirror)
			)
		)
		(property "License" "Apache-2.0"
			(at 0 0 180)
			(unlocked yes)
			(layer "B.Fab")
			(hide yes)
			(effects
				(font
					(size 1 1)
					(thickness 0.15)
				)
				(justify mirror)
			)
		)
		(property "Author" "Antmicro"
			(at 0 0 180)
			(unlocked yes)
			(layer "B.Fab")
			(hide yes)
			(effects
				(font
					(size 1 1)
					(thickness 0.15)
				)
				(justify mirror)
			)
		)
		(property "Voltage" "25V"
			(at 0 0 180)
			(unlocked yes)
			(layer "B.Fab")
			(hide yes)
			(effects
				(font
					(size 1 1)
					(thickness 0.15)
				)
				(justify mirror)
			)
		)
		(property "Dielectric" "X5R"
			(at 0 0 180)
			(unlocked yes)
			(layer "B.Fab")
			(hide yes)
			(effects
				(font
					(size 1 1)
					(thickness 0.15)
				)
				(justify mirror)
			)
		)
		(property "Public" "False"
			(at 0 0 180)
			(unlocked yes)
			(layer "B.Fab")
			(hide yes)
			(effects
				(font
					(size 1 1)
					(thickness 0.15)
				)
				(justify mirror)
			)
		)
		(sheetname "/USB Debug, PD/")
		(sheetfile "usb_debug_pd.kicad_sch")
		(attr smd)
		(fp_line
			(start -0.3 0.7)
			(end 0.3 0.7)
			(stroke
				(width 0.15)
				(type solid)
			)
			(layer "B.SilkS")
		)
		(fp_line
			(start -0.3 -0.7)
			(end 0.3 -0.7)
			(stroke
				(width 0.15)
				(type solid)
			)
			(layer "B.SilkS")
		)
		(fp_poly
			(pts
				(xy 1.95 0.9) (xy -1.95 0.9) (xy -1.95 -0.9) (xy 1.95 -0.9)
			)
			(stroke
				(width 0.05)
				(type default)
			)
			(fill no)
			(layer "B.CrtYd")
		)
		(fp_poly
			(pts
				(xy -0.95 0.675001) (xy 0.95 0.675001) (xy 0.95 -0.675001) (xy -0.95 -0.675001)
			)
			(stroke
				(width 0.15)
				(type solid)
			)
			(fill no)
			(layer "B.Fab")
		)
		(fp_text user "${REFERENCE}"
			(at -1.899999 -3.947 0)
			(layer "B.Fab")
			(effects
				(font
					(size 0.7 0.7)
					(thickness 0.15)
				)
				(justify left bottom mirror)
			)
		)
		(fp_text user "License: Apache-2.0"
			(at -1.9 -4.947 0)
			(layer "B.Fab")
			(effects
				(font
					(size 0.7 0.7)
					(thickness 0.15)
				)
				(justify left bottom mirror)
			)
		)
		(fp_text user "Author: Antmicro"
			(at -1.9 -5.947 0)
			(layer "B.Fab")
			(effects
				(font
					(size 0.7 0.7)
					(thickness 0.15)
				)
				(justify left bottom mirror)
			)
		)
		(pad "1" smd roundrect
			(at -1.099999 0 180)
			(size 1.2 1.3)
			(layers "B.Cu" "B.Mask" "B.Paste")
			(roundrect_rratio 0.25)
			(net 176 "/USB Debug, PD/USBC0_VBUS")
			(pintype "passive")
		)
		(pad "2" smd roundrect
			(at 1.099999 0 180)
			(size 1.2 1.3)
			(layers "B.Cu" "B.Mask" "B.Paste")
			(roundrect_rratio 0.25)
			(net 1 "GND")
			(pintype "passive")
		)
	)
	(footprint "antmicro-footprints:R_0402_1005Metric"
		(layer "B.Cu")
		(at 227.2 109.4 -90)
		(descr "Resistor SMD 0402")
		(tags "resistor SMD 0402")
		(property "Reference" "R266"
			(at -3.84 -0.285 90)
			(layer "B.SilkS")
			(effects
				(font
					(size 0.7 0.7)
					(thickness 0.15)
				)
				(justify left bottom mirror)
			)
		)
		(property "Value" "R_10k_0402"
			(at -1.011843 -1.772047 90)
			(layer "B.Fab")
			(effects
				(font
					(size 0.7 0.7)
					(thickness 0.15)
				)
				(justify left bottom mirror)
			)
		)
		(property "Datasheet" "https://www.bourns.com/docs/product-datasheets/cr.pdf"
			(at 0 0 90)
			(layer "B.Fab")
			(hide yes)
			(effects
				(font
					(size 1.27 1.27)
					(thickness 0.15)
				)
				(justify mirror)
			)
		)
		(property "Description" "SMD Chip Resistor, 10 kohm, ± 1%, 62.5 mW, 0402 [1005 Metric], Thick Film, General Purpose"
			(at 0 0 90)
			(layer "B.Fab")
			(hide yes)
			(effects
				(font
					(size 1.27 1.27)
					(thickness 0.15)
				)
				(justify mirror)
			)
		)
		(property "Manufacturer" "Bourns"
			(at 0 0 90)
			(unlocked yes)
			(layer "B.Fab")
			(hide yes)
			(effects
				(font
					(size 1 1)
					(thickness 0.15)
				)
				(justify mirror)
			)
		)
		(property "MPN" "CR0402-FX-1002GLF"
			(at 0 0 90)
			(unlocked yes)
			(layer "B.Fab")
			(hide yes)
			(effects
				(font
					(size 1 1)
					(thickness 0.15)
				)
				(justify mirror)
			)
		)
		(property "Val" "10k"
			(at 0 0 90)
			(unlocked yes)
			(layer "B.Fab")
			(hide yes)
			(effects
				(font
					(size 1 1)
					(thickness 0.15)
				)
				(justify mirror)
			)
		)
		(property "License" "Apache-2.0"
			(at 0 0 90)
			(unlocked yes)
			(layer "B.Fab")
			(hide yes)
			(effects
				(font
					(size 1 1)
					(thickness 0.15)
				)
				(justify mirror)
			)
		)
		(property "Author" "Antmicro"
			(at 0 0 90)
			(unlocked yes)
			(layer "B.Fab")
			(hide yes)
			(effects
				(font
					(size 1 1)
					(thickness 0.15)
				)
				(justify mirror)
			)
		)
		(property "Tolerance" "1%"
			(at 0 0 90)
			(unlocked yes)
			(layer "B.Fab")
			(hide yes)
			(effects
				(font
					(size 1 1)
					(thickness 0.15)
				)
				(justify mirror)
			)
		)
		(sheetname "/Recovery USB/")
		(sheetfile "recovery_usb.kicad_sch")
		(attr smd)
		(fp_rect
			(start -0.925 0.47)
			(end 0.925 -0.47)
			(stroke
				(width 0.05)
				(type default)
			)
			(fill no)
			(layer "B.CrtYd")
		)
		(fp_rect
			(start -0.5 0.25)
			(end 0.5 -0.25)
			(stroke
				(width 0.15)
				(type solid)
			)
			(fill no)
			(layer "B.Fab")
		)
		(fp_text user "License: Apache-2.0"
			(at -0.95 -5.169 90)
			(layer "B.Fab")
			(effects
				(font
					(size 0.7 0.7)
					(thickness 0.15)
				)
				(justify left bottom mirror)
			)
		)
		(fp_text user "Author: Antmicro"
			(at -0.95 -4.169 90)
			(layer "B.Fab")
			(effects
				(font
					(size 0.7 0.7)
					(thickness 0.15)
				)
				(justify left bottom mirror)
			)
		)
		(fp_text user "${REFERENCE}"
			(at -0.95 -3.168 90)
			(layer "B.Fab")
			(effects
				(font
					(size 0.7 0.7)
					(thickness 0.15)
				)
				(justify left bottom mirror)
			)
		)
		(pad "1" smd roundrect
			(at -0.48 0 270)
			(size 0.59 0.64)
			(layers "B.Cu" "B.Mask" "B.Paste")
			(roundrect_rratio 0.25)
			(net 2 "+3V3")
			(pintype "passive")
		)
		(pad "2" smd roundrect
			(at 0.48 0 270)
			(size 0.59 0.64)
			(layers "B.Cu" "B.Mask" "B.Paste")
			(roundrect_rratio 0.25)
			(net 889 "/Recovery USB/USBC2_ID")
			(pintype "passive")
		)
	)
	(footprint "antmicro-footprints:Spacer_Drill3.7mm_H2.5mm_9774025151R"
		(locked yes)
		(layer "B.Cu")
		(at 159.46 129.51 90)
		(descr "Spacer M=3 h=2.5mm fi=5.1mm")
		(property "Reference" "H10"
			(at -3.49 -0.975 0)
			(layer "B.SilkS")
			(effects
				(font
					(size 0.7 0.7)
					(thickness 0.15)
				)
				(justify right top mirror)
			)
		)
		(property "Value" "Spacer_Drill3.7mm_H2.5mm_9774025151R"
			(at 0 -4 90)
			(layer "B.Fab")
			(effects
				(font
					(size 0.7 0.7)
					(thickness 0.15)
				)
				(justify right top mirror)
			)
		)
		(property "Datasheet" "https://www.we-online.com/components/products/datasheet/9774025151R.pdf"
			(at 0 0 90)
			(layer "B.Fab")
			(hide yes)
			(effects
				(font
					(size 1.27 1.27)
					(thickness 0.15)
				)
				(justify mirror)
			)
		)
		(property "Description" "Spacer, SMT, Non Stop, Steel, Swage Round, 5.1 mm x 2.5 mm, M2.5 Thread, WA-SMSI Series"
			(at 0 0 90)
			(layer "B.Fab")
			(hide yes)
			(effects
				(font
					(size 1.27 1.27)
					(thickness 0.15)
				)
				(justify mirror)
			)
		)
		(property "Manufacturer" "Würth Elektronik"
			(at 0 0 270)
			(unlocked yes)
			(layer "B.Fab")
			(hide yes)
			(effects
				(font
					(size 1 1)
					(thickness 0.15)
				)
				(justify mirror)
			)
		)
		(property "MPN" "9774025151R"
			(at 0 0 270)
			(unlocked yes)
			(layer "B.Fab")
			(hide yes)
			(effects
				(font
					(size 1 1)
					(thickness 0.15)
				)
				(justify mirror)
			)
		)
		(property "Author" "Antmicro"
			(at 0 0 270)
			(unlocked yes)
			(layer "B.Fab")
			(hide yes)
			(effects
				(font
					(size 1 1)
					(thickness 0.15)
				)
				(justify mirror)
			)
		)
		(property "License" "Apache-2.0"
			(at 0 0 270)
			(unlocked yes)
			(layer "B.Fab")
			(hide yes)
			(effects
				(font
					(size 1 1)
					(thickness 0.15)
				)
				(justify mirror)
			)
		)
		(sheetname "/M.2/")
		(sheetfile "m2.kicad_sch")
		(solder_paste_margin_ratio -1)
		(attr smd)
		(fp_circle
			(center 0 0)
			(end 3.05 0)
			(stroke
				(width 0.05)
				(type solid)
			)
			(fill no)
			(layer "B.CrtYd")
		)
		(fp_circle
			(center 0 0)
			(end 2.6 0)
			(stroke
				(width 0.15)
				(type solid)
			)
			(fill no)
			(layer "B.Fab")
		)
		(fp_text user "${REFERENCE}"
			(at -9.6 -6.5 90)
			(layer "B.Fab")
			(effects
				(font
					(size 0.7 0.7)
					(thickness 0.15)
				)
				(justify right top mirror)
			)
		)
		(fp_text user "Author: Antmicro"
			(at -9.6 -7.7 90)
			(layer "B.Fab")
			(effects
				(font
					(size 0.7 0.7)
					(thickness 0.15)
				)
				(justify right top mirror)
			)
		)
		(fp_text user "License: Apache-2.0"
			(at -9.6 -8.9 90)
			(layer "B.Fab")
			(effects
				(font
					(size 0.7 0.7)
					(thickness 0.15)
				)
				(justify right top mirror)
			)
		)
		(pad "" smd custom
			(at -1.7 -1.7)
			(size 0.62 0.62)
			(layers "B.Paste")
			(thermal_bridge_angle 90)
			(options
				(clearance outline)
				(anchor circle)
			)
			(primitives
				(gr_arc
					(start 1.266786 0.24747)
					(mid 0.285453 -0.29439)
					(end -0.250195 -1.279127)
					(width 0.2)
				)
				(gr_arc
					(start 1.259603 0.339191)
					(mid 0.218448 -0.232561)
					(end -0.34334 -1.279127)
					(width 0.2)
				)
				(gr_arc
					(start 1.255279 0.431435)
					(mid 0.152481 -0.169693)
					(end -0.436309 -1.279127)
					(width 0.2)
				)
				(gr_arc
					(start 1.253811 0.524161)
					(mid 0.087542 -0.105784)
					(end -0.529126 -1.279127)
					(width 0.2)
				)
				(gr_arc
					(start 1.275473 0.621136)
					(mid 0.0309 -0.033527)
					(end -0.621807 -1.279127)
					(width 0.2)
				)
				(gr_arc
					(start 1.263664 0.711602)
					(mid -0.037759 0.026651)
					(end -0.71437 -1.279127)
					(width 0.2)
				)
				(gr_arc
					(start 1.253435 0.802342)
					(mid -0.105837 0.087395)
					(end -0.806826 -1.279127)
					(width 0.2)
				)
				(gr_arc
					(start 1.267475 0.897258)
					(mid -0.165236 0.156885)
					(end -0.899187 -1.279127)
					(width 0.2)
				)
				(gr_arc
					(start 1.270645 0.990112)
					(mid -0.228522 0.222449)
					(end -0.991463 -1.279127)
					(width 0.2)
				)
				(gr_arc
					(start 1.266278 1.081674)
					(mid -0.294507 0.285313)
					(end -1.083663 -1.279127)
					(width 0.2)
				)
				(gr_line
					(start 1.279127 0.250195)
					(end 1.279127 1.083663)
					(width 0.2)
				)
				(gr_line
					(start -0.250195 -1.279127)
					(end -1.083663 -1.279127)
					(width 0.2)
				)
			)
		)
		(pad "" smd custom
			(at -1.7 1.7 90)
			(size 0.62 0.62)
			(layers "B.Paste")
			(thermal_bridge_angle 90)
			(options
				(clearance outline)
				(anchor circle)
			)
			(primitives
				(gr_arc
					(start 1.266786 0.24747)
					(mid 0.285453 -0.29439)
					(end -0.250195 -1.279127)
					(width 0.2)
				)
				(gr_arc
					(start 1.259603 0.339191)
					(mid 0.218448 -0.232561)
					(end -0.34334 -1.279127)
					(width 0.2)
				)
				(gr_arc
					(start 1.255279 0.431435)
					(mid 0.152481 -0.169693)
					(end -0.436309 -1.279127)
					(width 0.2)
				)
				(gr_arc
					(start 1.253811 0.524161)
					(mid 0.087542 -0.105784)
					(end -0.529126 -1.279127)
					(width 0.2)
				)
				(gr_arc
					(start 1.275473 0.621136)
					(mid 0.0309 -0.033527)
					(end -0.621807 -1.279127)
					(width 0.2)
				)
				(gr_arc
					(start 1.263664 0.711602)
					(mid -0.037759 0.026651)
					(end -0.71437 -1.279127)
					(width 0.2)
				)
				(gr_arc
					(start 1.253435 0.802342)
					(mid -0.105837 0.087395)
					(end -0.806826 -1.279127)
					(width 0.2)
				)
				(gr_arc
					(start 1.267475 0.897258)
					(mid -0.165236 0.156885)
					(end -0.899187 -1.279127)
					(width 0.2)
				)
				(gr_arc
					(start 1.270645 0.990112)
					(mid -0.228522 0.222449)
					(end -0.991463 -1.279127)
					(width 0.2)
				)
				(gr_arc
					(start 1.266278 1.081674)
					(mid -0.294507 0.285313)
					(end -1.083663 -1.279127)
					(width 0.2)
				)
				(gr_line
					(start 1.279127 0.250195)
					(end 1.279127 1.083663)
					(width 0.2)
				)
				(gr_line
					(start -0.250195 -1.279127)
					(end -1.083663 -1.279127)
					(width 0.2)
				)
			)
		)
		(pad "" smd custom
			(at 1.7 -1.7 270)
			(size 0.62 0.62)
			(layers "B.Paste")
			(thermal_bridge_angle 90)
			(options
				(clearance outline)
				(anchor circle)
			)
			(primitives
				(gr_arc
					(start 1.266786 0.24747)
					(mid 0.285453 -0.29439)
					(end -0.250195 -1.279127)
					(width 0.2)
				)
				(gr_arc
					(start 1.259603 0.339191)
					(mid 0.218448 -0.232561)
					(end -0.34334 -1.279127)
					(width 0.2)
				)
				(gr_arc
					(start 1.255279 0.431435)
					(mid 0.152481 -0.169693)
					(end -0.436309 -1.279127)
					(width 0.2)
				)
				(gr_arc
					(start 1.253811 0.524161)
					(mid 0.087542 -0.105784)
					(end -0.529126 -1.279127)
					(width 0.2)
				)
				(gr_arc
					(start 1.275473 0.621136)
					(mid 0.0309 -0.033527)
					(end -0.621807 -1.279127)
					(width 0.2)
				)
				(gr_arc
					(start 1.263664 0.711602)
					(mid -0.037759 0.026651)
					(end -0.71437 -1.279127)
					(width 0.2)
				)
				(gr_arc
					(start 1.253435 0.802342)
					(mid -0.105837 0.087395)
					(end -0.806826 -1.279127)
					(width 0.2)
				)
				(gr_arc
					(start 1.267475 0.897258)
					(mid -0.165236 0.156885)
					(end -0.899187 -1.279127)
					(width 0.2)
				)
				(gr_arc
					(start 1.270645 0.990112)
					(mid -0.228522 0.222449)
					(end -0.991463 -1.279127)
					(width 0.2)
				)
				(gr_arc
					(start 1.266278 1.081674)
					(mid -0.294507 0.285313)
					(end -1.083663 -1.279127)
					(width 0.2)
				)
				(gr_line
					(start 1.279127 0.250195)
					(end 1.279127 1.083663)
					(width 0.2)
				)
				(gr_line
					(start -0.250195 -1.279127)
					(end -1.083663 -1.279127)
					(width 0.2)
				)
			)
		)
		(pad "" smd custom
			(at 1.7 1.7 180)
			(size 0.62 0.62)
			(layers "B.Paste")
			(thermal_bridge_angle 90)
			(options
				(clearance outline)
				(anchor circle)
			)
			(primitives
				(gr_arc
					(start 1.266786 0.24747)
					(mid 0.285453 -0.29439)
					(end -0.250195 -1.279127)
					(width 0.2)
				)
				(gr_arc
					(start 1.259603 0.339191)
					(mid 0.218448 -0.232561)
					(end -0.34334 -1.279127)
					(width 0.2)
				)
				(gr_arc
					(start 1.255279 0.431435)
					(mid 0.152481 -0.169693)
					(end -0.436309 -1.279127)
					(width 0.2)
				)
				(gr_arc
					(start 1.253811 0.524161)
					(mid 0.087542 -0.105784)
					(end -0.529126 -1.279127)
					(width 0.2)
				)
				(gr_arc
					(start 1.275473 0.621136)
					(mid 0.0309 -0.033527)
					(end -0.621807 -1.279127)
					(width 0.2)
				)
				(gr_arc
					(start 1.263664 0.711602)
					(mid -0.037759 0.026651)
					(end -0.71437 -1.279127)
					(width 0.2)
				)
				(gr_arc
					(start 1.253435 0.802342)
					(mid -0.105837 0.087395)
					(end -0.806826 -1.279127)
					(width 0.2)
				)
				(gr_arc
					(start 1.267475 0.897258)
					(mid -0.165236 0.156885)
					(end -0.899187 -1.279127)
					(width 0.2)
				)
				(gr_arc
					(start 1.270645 0.990112)
					(mid -0.228522 0.222449)
					(end -0.991463 -1.279127)
					(width 0.2)
				)
				(gr_arc
					(start 1.266278 1.081674)
					(mid -0.294507 0.285313)
					(end -1.083663 -1.279127)
					(width 0.2)
				)
				(gr_line
					(start 1.279127 0.250195)
					(end 1.279127 1.083663)
					(width 0.2)
				)
				(gr_line
					(start -0.250195 -1.279127)
					(end -1.083663 -1.279127)
					(width 0.2)
				)
			)
		)
		(pad "1" thru_hole circle
			(at 0 0 90)
			(size 6 6)
			(drill 3.7)
			(layers "*.Cu" "*.Mask")
			(remove_unused_layers no)
			(net 1 "GND")
			(pintype "passive")
		)
	)
)
